(kicad_pcb
	(version 20260206)
	(generator "pcbnew")
	(generator_version "10.0")
	(general
		(thickness 1.6)
		(legacy_teardrops no)
	)
	(paper "A4")
	(title_block
		(title "03242023_DA0F0TMBIJ0_F0T_Motherboard_J_brd_V01_OCP.brd")
		(comment 1 "Grand Teton / footprints 3692-3697 of 6105")
	)
	(layers
		(0 "F.Cu" signal "TOP")
		(4 "In1.Cu" signal "GND")
		(6 "In2.Cu" signal "IN1")
		(8 "In3.Cu" signal "GND1")
		(10 "In4.Cu" signal "IN2")
		(12 "In5.Cu" signal "GND2")
		(14 "In6.Cu" signal "IN3")
		(16 "In7.Cu" signal "GND3")
		(18 "In8.Cu" signal "VCC")
		(20 "In9.Cu" signal "VCC1")
		(22 "In10.Cu" signal "GND4")
		(24 "In11.Cu" signal "IN4")
		(26 "In12.Cu" signal "GND5")
		(28 "In13.Cu" signal "IN5")
		(30 "In14.Cu" signal "GND6")
		(32 "In15.Cu" signal "IN6")
		(34 "In16.Cu" signal "GND7")
		(2 "B.Cu" signal "BOTTOM")
		(9 "F.Adhes" user "F.Adhesive")
		(11 "B.Adhes" user "B.Adhesive")
		(13 "F.Paste" user "Package Geometry/Pastemask Top")
		(15 "B.Paste" user "Package Geometry/Pastemask Bottom")
		(5 "F.SilkS" user "Ref Des/Silkscreen Top")
		(7 "B.SilkS" user "Ref Des/Silkscreen Bottom")
		(1 "F.Mask" user "Board Geometry/Soldermask Top")
		(3 "B.Mask" user "Board Geometry/Soldermask Bottom")
		(17 "Dwgs.User" user "User.Drawings")
		(19 "Cmts.User" user "User.Comments")
		(21 "Eco1.User" user "User.Eco1")
		(23 "Eco2.User" user "User.Eco2")
		(25 "Edge.Cuts" user "Board Geometry/Outline")
		(27 "Margin" user)
		(31 "F.CrtYd" user "Package Geometry/Place Bound Top")
		(29 "B.CrtYd" user "Package Geometry/Place Bound Bottom")
		(35 "F.Fab" user "Ref Des/Assembly Top")
		(33 "B.Fab" user "Ref Des/Assembly Bottom")
	)
	(footprint ""
		(layer "F.Cu")
		(at 172.36948 -424.398948)
		(property "Reference" "U195"
			(at -1.41478 -2.86639 0)
			(unlocked yes)
			(layer "F.SilkS")
			(effects
				(font
					(size 0.7874 0.5842)
					(thickness 0.1524)
				)
				(justify left)
			)
		)
		(property "Value" ""
			(at 0 0 0)
			(layer "F.Fab")
			(effects
				(font
					(size 1.27 1.27)
				)
			)
		)
		(duplicate_pad_numbers_are_jumpers no)
		(fp_line
			(start -1.3462 -1.100074)
			(end -0.670052 -1.100074)
			(stroke
				(width 0.1524)
				(type default)
			)
			(layer "F.SilkS")
		)
		(fp_line
			(start -1.3462 1.100074)
			(end -1.3462 -1.100074)
			(stroke
				(width 0.1524)
				(type default)
			)
			(layer "F.SilkS")
		)
		(fp_line
			(start -0.670052 -1.100074)
			(end 0 -0.381)
			(stroke
				(width 0.1524)
				(type default)
			)
			(layer "F.SilkS")
		)
		(fp_line
			(start 0 -0.381)
			(end 0.670052 -1.100074)
			(stroke
				(width 0.1524)
				(type default)
			)
			(layer "F.SilkS")
		)
		(fp_line
			(start 0.670052 -1.100074)
			(end 1.3462 -1.100074)
			(stroke
				(width 0.1524)
				(type default)
			)
			(layer "F.SilkS")
		)
		(fp_line
			(start 1.3462 -1.100074)
			(end 1.3462 1.100074)
			(stroke
				(width 0.1524)
				(type default)
			)
			(layer "F.SilkS")
		)
		(fp_line
			(start 1.3462 1.100074)
			(end -1.3462 1.100074)
			(stroke
				(width 0.1524)
				(type default)
			)
			(layer "F.SilkS")
		)
		(fp_poly
			(pts
				(xy -1.049274 -1.31826) (xy -1.430274 -2.08026) (xy -0.668274 -2.08026)
			)
			(stroke
				(width 0)
				(type default)
			)
			(fill yes)
			(layer "F.SilkS")
		)
		(fp_line
			(start -1.100074 -0.8001)
			(end -0.670052 -0.8001)
			(stroke
				(width 0.1)
				(type default)
			)
			(layer "F.Fab")
		)
		(fp_line
			(start -1.100074 0.8001)
			(end -1.100074 -0.8001)
			(stroke
				(width 0.1)
				(type default)
			)
			(layer "F.Fab")
		)
		(fp_line
			(start -0.670052 -1.100074)
			(end 0.670052 -1.100074)
			(stroke
				(width 0.1)
				(type default)
			)
			(layer "F.Fab")
		)
		(fp_line
			(start -0.670052 -0.8001)
			(end -0.670052 -1.100074)
			(stroke
				(width 0.1)
				(type default)
			)
			(layer "F.Fab")
		)
		(fp_line
			(start -0.670052 0.8001)
			(end -1.100074 0.8001)
			(stroke
				(width 0.1)
				(type default)
			)
			(layer "F.Fab")
		)
		(fp_line
			(start -0.670052 0.8001)
			(end -0.670052 -0.8001)
			(stroke
				(width 0.1)
				(type default)
			)
			(layer "F.Fab")
		)
		(fp_line
			(start -0.670052 1.100074)
			(end -0.670052 0.8001)
			(stroke
				(width 0.1)
				(type default)
			)
			(layer "F.Fab")
		)
		(fp_line
			(start 0.670052 -1.100074)
			(end 0.670052 -0.8001)
			(stroke
				(width 0.1)
				(type default)
			)
			(layer "F.Fab")
		)
		(fp_line
			(start 0.670052 -0.8001)
			(end 0.670052 0.8001)
			(stroke
				(width 0.1)
				(type default)
			)
			(layer "F.Fab")
		)
		(fp_line
			(start 0.670052 -0.8001)
			(end 1.100074 -0.8001)
			(stroke
				(width 0.1)
				(type default)
			)
			(layer "F.Fab")
		)
		(fp_line
			(start 0.670052 0.8001)
			(end 0.670052 1.100074)
			(stroke
				(width 0.1)
				(type default)
			)
			(layer "F.Fab")
		)
		(fp_line
			(start 0.670052 1.100074)
			(end -0.670052 1.100074)
			(stroke
				(width 0.1)
				(type default)
			)
			(layer "F.Fab")
		)
		(fp_line
			(start 1.100074 -0.8001)
			(end 1.100074 0.8001)
			(stroke
				(width 0.1)
				(type default)
			)
			(layer "F.Fab")
		)
		(fp_line
			(start 1.100074 0.8001)
			(end 0.670052 0.8001)
			(stroke
				(width 0.1)
				(type default)
			)
			(layer "F.Fab")
		)
		(fp_poly
			(pts
				(xy -1.524 -0.649986) (xy -2.286 -1.030986) (xy -2.286 -0.268986)
			)
			(stroke
				(width 0)
				(type default)
			)
			(fill yes)
			(layer "F.Fab")
		)
		(pad "1" smd rect
			(at -0.94996 -0.649986 270)
			(size 0.4064 0.508)
			(layers "F.Cu" "F.Mask" "F.Paste")
			(net "BMC_MONITER_R")
		)
		(pad "2" smd rect
			(at -0.94996 0 270)
			(size 0.4064 0.508)
			(layers "F.Cu" "F.Mask" "F.Paste")
			(net "GND")
		)
		(pad "3" smd rect
			(at -0.94996 0.649986 270)
			(size 0.4064 0.508)
			(layers "F.Cu" "F.Mask" "F.Paste")
			(net "RST_SWB_BIC_R_N")
		)
		(pad "4" smd rect
			(at 0.94996 0.649986 270)
			(size 0.4064 0.508)
			(layers "F.Cu" "F.Mask" "F.Paste")
			(net "RST_SWB_BIC_BUF_R_N")
		)
		(pad "5" smd rect
			(at 0.94996 0 270)
			(size 0.4064 0.508)
			(layers "F.Cu" "F.Mask" "F.Paste")
			(net "P3V3_AUX")
		)
		(pad "6" smd rect
			(at 0.94996 -0.649986 270)
			(size 0.4064 0.508)
			(layers "F.Cu" "F.Mask" "F.Paste")
			(net "BMC_MONITER_BUF_R")
		)
	)
	(footprint ""
		(layer "F.Cu")
		(at 460.092044 -76.57211 90)
		(property "Reference" "PC2262"
			(at 0 0 90)
			(layer "F.SilkS")
			(hide yes)
			(effects
				(font
					(size 1.27 1.27)
				)
			)
		)
		(property "Value" ""
			(at 0 0 90)
			(layer "F.Fab")
			(effects
				(font
					(size 1.27 1.27)
				)
			)
		)
		(duplicate_pad_numbers_are_jumpers no)
		(fp_line
			(start 1.524 -0.762)
			(end 1.524 0.762)
			(stroke
				(width 0.1524)
				(type default)
			)
			(layer "F.SilkS")
		)
		(fp_line
			(start -1.524 -0.762)
			(end 1.524 -0.762)
			(stroke
				(width 0.1524)
				(type default)
			)
			(layer "F.SilkS")
		)
		(fp_line
			(start 1.524 0.762)
			(end -1.524 0.762)
			(stroke
				(width 0.1524)
				(type default)
			)
			(layer "F.SilkS")
		)
		(fp_line
			(start -1.524 0.762)
			(end -1.524 -0.762)
			(stroke
				(width 0.1524)
				(type default)
			)
			(layer "F.SilkS")
		)
		(fp_line
			(start 1.1049 -0.724916)
			(end -1.1049 -0.724916)
			(stroke
				(width 0.1)
				(type default)
			)
			(layer "F.Fab")
		)
		(fp_line
			(start -1.1049 -0.724916)
			(end -1.1049 0.724916)
			(stroke
				(width 0.1)
				(type default)
			)
			(layer "F.Fab")
		)
		(fp_line
			(start 1.1049 0.724916)
			(end 1.1049 -0.724916)
			(stroke
				(width 0.1)
				(type default)
			)
			(layer "F.Fab")
		)
		(fp_line
			(start -1.1049 0.724916)
			(end 1.1049 0.724916)
			(stroke
				(width 0.1)
				(type default)
			)
			(layer "F.Fab")
		)
		(pad "1" smd rect
			(at -0.889 0 270)
			(size 1.016 1.27)
			(layers "F.Cu" "F.Mask" "F.Paste")
			(net "SW_P3V3_AUX_FLT")
		)
		(pad "2" smd rect
			(at 0.889 0 270)
			(size 1.016 1.27)
			(layers "F.Cu" "F.Mask" "F.Paste")
			(net "GND")
		)
	)
	(footprint ""
		(layer "F.Cu")
		(at 293.265098 -408.7749)
		(property "Reference" "U345"
			(at -0.37084 2.595372 0)
			(unlocked yes)
			(layer "F.SilkS")
			(effects
				(font
					(size 0.7874 0.5842)
					(thickness 0.1524)
				)
				(justify left)
			)
		)
		(property "Value" ""
			(at 0 0 0)
			(layer "F.Fab")
			(effects
				(font
					(size 1.27 1.27)
				)
			)
		)
		(duplicate_pad_numbers_are_jumpers no)
		(fp_line
			(start -1.448308 -1.549908)
			(end -0.774954 -1.549908)
			(stroke
				(width 0.1524)
				(type default)
			)
			(layer "F.SilkS")
		)
		(fp_line
			(start -1.448308 1.549908)
			(end -1.448308 -1.549908)
			(stroke
				(width 0.1524)
				(type default)
			)
			(layer "F.SilkS")
		)
		(fp_line
			(start -0.774954 -1.549908)
			(end 0 -0.533908)
			(stroke
				(width 0.1524)
				(type default)
			)
			(layer "F.SilkS")
		)
		(fp_line
			(start 0 -0.533908)
			(end 0.774954 -1.549908)
			(stroke
				(width 0.1524)
				(type default)
			)
			(layer "F.SilkS")
		)
		(fp_line
			(start 1.448308 -1.549908)
			(end 1.448308 1.549908)
			(stroke
				(width 0.1524)
				(type default)
			)
			(layer "F.SilkS")
		)
		(fp_line
			(start 1.448308 1.549908)
			(end -1.448308 1.549908)
			(stroke
				(width 0.1524)
				(type default)
			)
			(layer "F.SilkS")
		)
		(fp_rect
			(start -1.549908 -1.549908)
			(end -0.787908 -1.880108)
			(stroke
				(width 0)
				(type default)
			)
			(fill yes)
			(layer "F.SilkS")
		)
		(fp_line
			(start -1.549908 -1.549908)
			(end 1.549908 -1.549908)
			(stroke
				(width 0.1)
				(type default)
			)
			(layer "F.Fab")
		)
		(fp_line
			(start -1.549908 1.549908)
			(end -1.549908 -1.549908)
			(stroke
				(width 0.1)
				(type default)
			)
			(layer "F.Fab")
		)
		(fp_line
			(start 1.549908 -1.549908)
			(end 1.549908 1.549908)
			(stroke
				(width 0.1)
				(type default)
			)
			(layer "F.Fab")
		)
		(fp_line
			(start 1.549908 1.549908)
			(end -1.549908 1.549908)
			(stroke
				(width 0.1)
				(type default)
			)
			(layer "F.Fab")
		)
		(fp_rect
			(start -1.549908 -1.549908)
			(end -0.787908 -1.880108)
			(stroke
				(width 0)
				(type default)
			)
			(fill yes)
			(layer "F.Fab")
		)
		(pad "1" smd rect
			(at -2.350008 -0.975106 270)
			(size 0.4318 1.4986)
			(layers "F.Cu" "F.Mask" "F.Paste")
			(net "P3V3_AUX")
		)
		(pad "2" smd rect
			(at -2.350008 -0.32512 270)
			(size 0.4318 1.4986)
			(layers "F.Cu" "F.Mask" "F.Paste")
			(net "P12V_HSC_TEMP_D+")
		)
		(pad "3" smd rect
			(at -2.350008 0.32512 270)
			(size 0.4318 1.4986)
			(layers "F.Cu" "F.Mask" "F.Paste")
			(net "P12V_HSC_TEMP_D-")
		)
		(pad "4" smd rect
			(at -2.350008 0.975106 270)
			(size 0.4318 1.4986)
			(layers "F.Cu" "F.Mask" "F.Paste")
			(net "P12V_HSC_T_CRIT_N")
		)
		(pad "5" smd rect
			(at 2.350008 0.975106 270)
			(size 0.4318 1.4986)
			(layers "F.Cu" "F.Mask" "F.Paste")
			(net "GND")
		)
		(pad "6" smd rect
			(at 2.350008 0.32512 270)
			(size 0.4318 1.4986)
			(layers "F.Cu" "F.Mask" "F.Paste")
			(net "P12V_HSC_TEMP_ALERT_N")
		)
		(pad "7" smd rect
			(at 2.350008 -0.32512 270)
			(size 0.4318 1.4986)
			(layers "F.Cu" "F.Mask" "F.Paste")
			(net "P12V_HSC_TEMP_SDA")
		)
		(pad "8" smd rect
			(at 2.350008 -0.975106 270)
			(size 0.4318 1.4986)
			(layers "F.Cu" "F.Mask" "F.Paste")
			(net "P12V_HSC_TEMP_SCL")
		)
	)
	(footprint ""
		(layer "F.Cu")
		(at 220.087444 -98.164904 180)
		(property "Reference" "R2221"
			(at 0 0 180)
			(layer "F.SilkS")
			(hide yes)
			(effects
				(font
					(size 1.27 1.27)
				)
			)
		)
		(property "Value" ""
			(at 0 0 180)
			(layer "F.Fab")
			(effects
				(font
					(size 1.27 1.27)
				)
			)
		)
		(duplicate_pad_numbers_are_jumpers no)
		(fp_line
			(start 0.7874 0.4064)
			(end -0.7874 0.4064)
			(stroke
				(width 0.1524)
				(type default)
			)
			(layer "F.SilkS")
		)
		(fp_line
			(start 0.7874 -0.4064)
			(end 0.7874 0.4064)
			(stroke
				(width 0.1524)
				(type default)
			)
			(layer "F.SilkS")
		)
		(fp_line
			(start -0.7874 0.4064)
			(end -0.7874 -0.4064)
			(stroke
				(width 0.1524)
				(type default)
			)
			(layer "F.SilkS")
		)
		(fp_line
			(start -0.7874 -0.4064)
			(end 0.7874 -0.4064)
			(stroke
				(width 0.1524)
				(type default)
			)
			(layer "F.SilkS")
		)
		(fp_line
			(start 0.67945 0.3048)
			(end 0.120396 0.3048)
			(stroke
				(width 0.1)
				(type default)
			)
			(layer "F.Fab")
		)
		(fp_line
			(start 0.67945 -0.3048)
			(end 0.67945 0.3048)
			(stroke
				(width 0.1)
				(type default)
			)
			(layer "F.Fab")
		)
		(fp_line
			(start 0.12065 -0.2794)
			(end 0.12065 -0.3048)
			(stroke
				(width 0.1)
				(type default)
			)
			(layer "F.Fab")
		)
		(fp_line
			(start 0.12065 -0.3048)
			(end 0.67945 -0.3048)
			(stroke
				(width 0.1)
				(type default)
			)
			(layer "F.Fab")
		)
		(fp_line
			(start 0.120396 0.3048)
			(end 0.120396 0.2794)
			(stroke
				(width 0.1)
				(type default)
			)
			(layer "F.Fab")
		)
		(fp_line
			(start 0.120396 0.2794)
			(end -0.12065 0.2794)
			(stroke
				(width 0.1)
				(type default)
			)
			(layer "F.Fab")
		)
		(fp_line
			(start -0.12065 0.3048)
			(end -0.67945 0.3048)
			(stroke
				(width 0.1)
				(type default)
			)
			(layer "F.Fab")
		)
		(fp_line
			(start -0.12065 0.2794)
			(end -0.12065 0.3048)
			(stroke
				(width 0.1)
				(type default)
			)
			(layer "F.Fab")
		)
		(fp_line
			(start -0.12065 -0.2794)
			(end 0.12065 -0.2794)
			(stroke
				(width 0.1)
				(type default)
			)
			(layer "F.Fab")
		)
		(fp_line
			(start -0.12065 -0.305054)
			(end -0.12065 -0.2794)
			(stroke
				(width 0.1)
				(type default)
			)
			(layer "F.Fab")
		)
		(fp_line
			(start -0.67945 0.3048)
			(end -0.67945 -0.305054)
			(stroke
				(width 0.1)
				(type default)
			)
			(layer "F.Fab")
		)
		(fp_line
			(start -0.67945 -0.305054)
			(end -0.12065 -0.305054)
			(stroke
				(width 0.1)
				(type default)
			)
			(layer "F.Fab")
		)
		(pad "1" smd circle
			(at -0.40005 0 180)
			(size 0 0)
			(layers "F.Cu" "F.Mask" "F.Paste")
			(net "P12V_AUX")
		)
		(pad "2" smd circle
			(at 0.40005 0 180)
			(size 0 0)
			(layers "F.Cu" "F.Mask" "F.Paste")
			(net "A_P12V_STBY_FP_TRIGGER")
		)
	)
	(footprint ""
		(layer "F.Cu")
		(at 366.48263 -238.162338 90)
		(property "Reference" "C412"
			(at 0 0 90)
			(layer "F.SilkS")
			(hide yes)
			(effects
				(font
					(size 1.27 1.27)
				)
			)
		)
		(property "Value" ""
			(at 0 0 90)
			(layer "F.Fab")
			(effects
				(font
					(size 1.27 1.27)
				)
			)
		)
		(duplicate_pad_numbers_are_jumpers no)
		(fp_line
			(start 0.7874 -0.4064)
			(end 0.7874 0.4064)
			(stroke
				(width 0.1524)
				(type default)
			)
			(layer "F.SilkS")
		)
		(fp_line
			(start -0.7874 -0.4064)
			(end 0.7874 -0.4064)
			(stroke
				(width 0.1524)
				(type default)
			)
			(layer "F.SilkS")
		)
		(fp_line
			(start 0.7874 0.4064)
			(end -0.7874 0.4064)
			(stroke
				(width 0.1524)
				(type default)
			)
			(layer "F.SilkS")
		)
		(fp_line
			(start -0.7874 0.4064)
			(end -0.7874 -0.4064)
			(stroke
				(width 0.1524)
				(type default)
			)
			(layer "F.SilkS")
		)
		(fp_line
			(start -0.12065 -0.305054)
			(end -0.12065 -0.2794)
			(stroke
				(width 0.1)
				(type default)
			)
			(layer "F.Fab")
		)
		(fp_line
			(start -0.67945 -0.305054)
			(end -0.12065 -0.305054)
			(stroke
				(width 0.1)
				(type default)
			)
			(layer "F.Fab")
		)
		(fp_line
			(start 0.67945 -0.3048)
			(end 0.67945 0.3048)
			(stroke
				(width 0.1)
				(type default)
			)
			(layer "F.Fab")
		)
		(fp_line
			(start 0.12065 -0.3048)
			(end 0.67945 -0.3048)
			(stroke
				(width 0.1)
				(type default)
			)
			(layer "F.Fab")
		)
		(fp_line
			(start 0.12065 -0.2794)
			(end 0.12065 -0.3048)
			(stroke
				(width 0.1)
				(type default)
			)
			(layer "F.Fab")
		)
		(fp_line
			(start -0.12065 -0.2794)
			(end 0.12065 -0.2794)
			(stroke
				(width 0.1)
				(type default)
			)
			(layer "F.Fab")
		)
		(fp_line
			(start 0.120396 0.2794)
			(end -0.12065 0.2794)
			(stroke
				(width 0.1)
				(type default)
			)
			(layer "F.Fab")
		)
		(fp_line
			(start -0.12065 0.2794)
			(end -0.12065 0.3048)
			(stroke
				(width 0.1)
				(type default)
			)
			(layer "F.Fab")
		)
		(fp_line
			(start 0.67945 0.3048)
			(end 0.120396 0.3048)
			(stroke
				(width 0.1)
				(type default)
			)
			(layer "F.Fab")
		)
		(fp_line
			(start 0.120396 0.3048)
			(end 0.120396 0.2794)
			(stroke
				(width 0.1)
				(type default)
			)
			(layer "F.Fab")
		)
		(fp_line
			(start -0.12065 0.3048)
			(end -0.67945 0.3048)
			(stroke
				(width 0.1)
				(type default)
			)
			(layer "F.Fab")
		)
		(fp_line
			(start -0.67945 0.3048)
			(end -0.67945 -0.305054)
			(stroke
				(width 0.1)
				(type default)
			)
			(layer "F.Fab")
		)
		(pad "1" smd circle
			(at -0.40005 0 90)
			(size 0 0)
			(layers "F.Cu" "F.Mask" "F.Paste")
			(net "PVCCINFAON_CPU0")
		)
		(pad "2" smd circle
			(at 0.40005 0 90)
			(size 0 0)
			(layers "F.Cu" "F.Mask" "F.Paste")
			(net "GND")
		)
	)
	(footprint ""
		(layer "F.Cu")
		(at 430.600104 -130.329178 180)
		(property "Reference" "R2391"
			(at 0 0 180)
			(layer "F.SilkS")
			(hide yes)
			(effects
				(font
					(size 1.27 1.27)
				)
			)
		)
		(property "Value" ""
			(at 0 0 180)
			(layer "F.Fab")
			(effects
				(font
					(size 1.27 1.27)
				)
			)
		)
		(duplicate_pad_numbers_are_jumpers no)
		(fp_line
			(start 0.7874 0.4064)
			(end -0.7874 0.4064)
			(stroke
				(width 0.1524)
				(type default)
			)
			(layer "F.SilkS")
		)
		(fp_line
			(start 0.7874 -0.4064)
			(end 0.7874 0.4064)
			(stroke
				(width 0.1524)
				(type default)
			)
			(layer "F.SilkS")
		)
		(fp_line
			(start -0.7874 0.4064)
			(end -0.7874 -0.4064)
			(stroke
				(width 0.1524)
				(type default)
			)
			(layer "F.SilkS")
		)
		(fp_line
			(start -0.7874 -0.4064)
			(end 0.7874 -0.4064)
			(stroke
				(width 0.1524)
				(type default)
			)
			(layer "F.SilkS")
		)
		(fp_line
			(start 0.67945 0.3048)
			(end 0.120396 0.3048)
			(stroke
				(width 0.1)
				(type default)
			)
			(layer "F.Fab")
		)
		(fp_line
			(start 0.67945 -0.3048)
			(end 0.67945 0.3048)
			(stroke
				(width 0.1)
				(type default)
			)
			(layer "F.Fab")
		)
		(fp_line
			(start 0.12065 -0.2794)
			(end 0.12065 -0.3048)
			(stroke
				(width 0.1)
				(type default)
			)
			(layer "F.Fab")
		)
		(fp_line
			(start 0.12065 -0.3048)
			(end 0.67945 -0.3048)
			(stroke
				(width 0.1)
				(type default)
			)
			(layer "F.Fab")
		)
		(fp_line
			(start 0.120396 0.3048)
			(end 0.120396 0.2794)
			(stroke
				(width 0.1)
				(type default)
			)
			(layer "F.Fab")
		)
		(fp_line
			(start 0.120396 0.2794)
			(end -0.12065 0.2794)
			(stroke
				(width 0.1)
				(type default)
			)
			(layer "F.Fab")
		)
		(fp_line
			(start -0.12065 0.3048)
			(end -0.67945 0.3048)
			(stroke
				(width 0.1)
				(type default)
			)
			(layer "F.Fab")
		)
		(fp_line
			(start -0.12065 0.2794)
			(end -0.12065 0.3048)
			(stroke
				(width 0.1)
				(type default)
			)
			(layer "F.Fab")
		)
		(fp_line
			(start -0.12065 -0.2794)
			(end 0.12065 -0.2794)
			(stroke
				(width 0.1)
				(type default)
			)
			(layer "F.Fab")
		)
		(fp_line
			(start -0.12065 -0.305054)
			(end -0.12065 -0.2794)
			(stroke
				(width 0.1)
				(type default)
			)
			(layer "F.Fab")
		)
		(fp_line
			(start -0.67945 0.3048)
			(end -0.67945 -0.305054)
			(stroke
				(width 0.1)
				(type default)
			)
			(layer "F.Fab")
		)
		(fp_line
			(start -0.67945 -0.305054)
			(end -0.12065 -0.305054)
			(stroke
				(width 0.1)
				(type default)
			)
			(layer "F.Fab")
		)
		(pad "1" smd circle
			(at -0.40005 0 180)
			(size 0 0)
			(layers "F.Cu" "F.Mask" "F.Paste")
			(net "SMB_VR_3V3AUX_SDA_R2")
		)
		(pad "2" smd circle
			(at 0.40005 0 180)
			(size 0 0)
			(layers "F.Cu" "F.Mask" "F.Paste")
			(net "SMB_DIO_PVCCINFAON_CPU0")
		)
	)
)
